# T6G (Grand Teton) — schematic netlist excerpt (pin names and nets, part order shuffled) for the footprints in the layout excerpt that follows; sources: Cadence DE-HDL packaged netlist, KiCad conversion of 04192023_DAF0TMB3IC0_F0TG_MB_C_brd_V02_OCP.brd

R3091  Q_RES  130 1% CHIP  pkg 0402LF  page 255 : A = LED_PWRGD_PVDD18_S5_P0_R ; B = P3V3_AUX
C232  Q_CAP  0.001UF 50V 10% EMPTY  pkg C0402  page 54 : A = JTAG_CPU1_TRST_N ; B = GND

(kicad_pcb
	(version 20260206)
	(generator "pcbnew")
	(generator_version "10.0")
	(general
		(thickness 1.6)
		(legacy_teardrops no)
	)
	(paper "A4")
	(title_block
		(title "04192023_DAF0TMB3IC0_F0TG_MB_C_brd_V02_OCP.brd")
		(comment 1 "Grand Teton / footprints 5575-5576 of 8354")
	)
	(layers
		(0 "F.Cu" signal "TOP")
		(4 "In1.Cu" signal "GND")
		(6 "In2.Cu" signal "IN1")
		(8 "In3.Cu" signal "GND1")
		(10 "In4.Cu" signal "IN2")
		(12 "In5.Cu" signal "GND2")
		(14 "In6.Cu" signal "IN3")
		(16 "In7.Cu" signal "GND3")
		(18 "In8.Cu" signal "VCC")
		(20 "In9.Cu" signal "VCC1")
		(22 "In10.Cu" signal "GND4")
		(24 "In11.Cu" signal "IN4")
		(26 "In12.Cu" signal "GND5")
		(28 "In13.Cu" signal "IN5")
		(30 "In14.Cu" signal "GND6")
		(32 "In15.Cu" signal "IN6")
		(34 "In16.Cu" signal "GND7")
		(2 "B.Cu" signal "BOTTOM")
		(9 "F.Adhes" user "F.Adhesive")
		(11 "B.Adhes" user "B.Adhesive")
		(13 "F.Paste" user "Package Geometry/Pastemask Top")
		(15 "B.Paste" user "Package Geometry/Pastemask Bottom")
		(5 "F.SilkS" user "Ref Des/Silkscreen Top")
		(7 "B.SilkS" user "Ref Des/Silkscreen Bottom")
		(1 "F.Mask" user "Board Geometry/Soldermask Top")
		(3 "B.Mask" user "Board Geometry/Soldermask Bottom")
		(17 "Dwgs.User" user "User.Drawings")
		(19 "Cmts.User" user "User.Comments")
		(21 "Eco1.User" user "User.Eco1")
		(23 "Eco2.User" user "User.Eco2")
		(25 "Edge.Cuts" user "Board Geometry/Outline")
		(27 "Margin" user)
		(31 "F.CrtYd" user "Package Geometry/Place Bound Top")
		(29 "B.CrtYd" user "Package Geometry/Place Bound Bottom")
		(35 "F.Fab" user "Ref Des/Assembly Top")
		(33 "B.Fab" user "Ref Des/Assembly Bottom")
	)
	(footprint ""
		(layer "B.Cu")
		(at 334.795876 -66.708782 90)
		(property "Reference" "R3091"
			(at 0 0 90)
			(layer "B.SilkS")
			(hide yes)
			(effects
				(font
					(size 1.27 1.27)
				)
				(justify mirror)
			)
		)
		(property "Value" ""
			(at 0 0 90)
			(layer "B.Fab")
			(effects
				(font
					(size 1.27 1.27)
				)
				(justify mirror)
			)
		)
		(duplicate_pad_numbers_are_jumpers no)
		(fp_line
			(start 0.7874 -0.4064)
			(end -0.7874 -0.4064)
			(stroke
				(width 0.1524)
				(type default)
			)
			(layer "B.SilkS")
		)
		(fp_line
			(start -0.7874 -0.4064)
			(end -0.7874 0.4064)
			(stroke
				(width 0.1524)
				(type default)
			)
			(layer "B.SilkS")
		)
		(fp_line
			(start 0.7874 0.4064)
			(end 0.7874 -0.4064)
			(stroke
				(width 0.1524)
				(type default)
			)
			(layer "B.SilkS")
		)
		(fp_line
			(start -0.7874 0.4064)
			(end 0.7874 0.4064)
			(stroke
				(width 0.1524)
				(type default)
			)
			(layer "B.SilkS")
		)
		(fp_line
			(start 0.67945 -0.305054)
			(end 0.12065 -0.305054)
			(stroke
				(width 0.1)
				(type default)
			)
			(layer "B.Fab")
		)
		(fp_line
			(start 0.12065 -0.305054)
			(end 0.12065 -0.2794)
			(stroke
				(width 0.1)
				(type default)
			)
			(layer "B.Fab")
		)
		(fp_line
			(start -0.12065 -0.3048)
			(end -0.67945 -0.3048)
			(stroke
				(width 0.1)
				(type default)
			)
			(layer "B.Fab")
		)
		(fp_line
			(start -0.67945 -0.3048)
			(end -0.67945 0.3048)
			(stroke
				(width 0.1)
				(type default)
			)
			(layer "B.Fab")
		)
		(fp_line
			(start 0.12065 -0.2794)
			(end -0.12065 -0.2794)
			(stroke
				(width 0.1)
				(type default)
			)
			(layer "B.Fab")
		)
		(fp_line
			(start -0.12065 -0.2794)
			(end -0.12065 -0.3048)
			(stroke
				(width 0.1)
				(type default)
			)
			(layer "B.Fab")
		)
		(fp_line
			(start 0.12065 0.2794)
			(end 0.12065 0.3048)
			(stroke
				(width 0.1)
				(type default)
			)
			(layer "B.Fab")
		)
		(fp_line
			(start -0.120396 0.2794)
			(end 0.12065 0.2794)
			(stroke
				(width 0.1)
				(type default)
			)
			(layer "B.Fab")
		)
		(fp_line
			(start 0.67945 0.3048)
			(end 0.67945 -0.305054)
			(stroke
				(width 0.1)
				(type default)
			)
			(layer "B.Fab")
		)
		(fp_line
			(start 0.12065 0.3048)
			(end 0.67945 0.3048)
			(stroke
				(width 0.1)
				(type default)
			)
			(layer "B.Fab")
		)
		(fp_line
			(start -0.120396 0.3048)
			(end -0.120396 0.2794)
			(stroke
				(width 0.1)
				(type default)
			)
			(layer "B.Fab")
		)
		(fp_line
			(start -0.67945 0.3048)
			(end -0.120396 0.3048)
			(stroke
				(width 0.1)
				(type default)
			)
			(layer "B.Fab")
		)
		(pad "1" smd circle
			(at 0.40005 0 270)
			(size 0 0)
			(layers "B.Cu" "B.Mask" "B.Paste")
			(net "LED_PWRGD_PVDD18_S5_P0_R")
		)
		(pad "2" smd circle
			(at -0.40005 0 270)
			(size 0 0)
			(layers "B.Cu" "B.Mask" "B.Paste")
			(net "P3V3_AUX")
		)
	)
	(footprint ""
		(layer "B.Cu")
		(at 151.275034 -201.977752 -90)
		(property "Reference" "C232"
			(at 0 0 90)
			(layer "B.SilkS")
			(hide yes)
			(effects
				(font
					(size 1.27 1.27)
				)
				(justify mirror)
			)
		)
		(property "Value" ""
			(at 0 0 90)
			(layer "B.Fab")
			(effects
				(font
					(size 1.27 1.27)
				)
				(justify mirror)
			)
		)
		(duplicate_pad_numbers_are_jumpers no)
		(fp_line
			(start -0.7874 0.4064)
			(end 0.7874 0.4064)
			(stroke
				(width 0.1524)
				(type default)
			)
			(layer "B.SilkS")
		)
		(fp_line
			(start 0.7874 0.4064)
			(end 0.7874 -0.4064)
			(stroke
				(width 0.1524)
				(type default)
			)
			(layer "B.SilkS")
		)
		(fp_line
			(start -0.7874 -0.4064)
			(end -0.7874 0.4064)
			(stroke
				(width 0.1524)
				(type default)
			)
			(layer "B.SilkS")
		)
		(fp_line
			(start 0.7874 -0.4064)
			(end -0.7874 -0.4064)
			(stroke
				(width 0.1524)
				(type default)
			)
			(layer "B.SilkS")
		)
		(fp_line
			(start -0.67945 0.3048)
			(end -0.120396 0.3048)
			(stroke
				(width 0.1)
				(type default)
			)
			(layer "B.Fab")
		)
		(fp_line
			(start -0.120396 0.3048)
			(end -0.120396 0.2794)
			(stroke
				(width 0.1)
				(type default)
			)
			(layer "B.Fab")
		)
		(fp_line
			(start 0.12065 0.3048)
			(end 0.67945 0.3048)
			(stroke
				(width 0.1)
				(type default)
			)
			(layer "B.Fab")
		)
		(fp_line
			(start 0.67945 0.3048)
			(end 0.67945 -0.305054)
			(stroke
				(width 0.1)
				(type default)
			)
			(layer "B.Fab")
		)
		(fp_line
			(start -0.120396 0.2794)
			(end 0.12065 0.2794)
			(stroke
				(width 0.1)
				(type default)
			)
			(layer "B.Fab")
		)
		(fp_line
			(start 0.12065 0.2794)
			(end 0.12065 0.3048)
			(stroke
				(width 0.1)
				(type default)
			)
			(layer "B.Fab")
		)
		(fp_line
			(start -0.12065 -0.2794)
			(end -0.12065 -0.3048)
			(stroke
				(width 0.1)
				(type default)
			)
			(layer "B.Fab")
		)
		(fp_line
			(start 0.12065 -0.2794)
			(end -0.12065 -0.2794)
			(stroke
				(width 0.1)
				(type default)
			)
			(layer "B.Fab")
		)
		(fp_line
			(start -0.67945 -0.3048)
			(end -0.67945 0.3048)
			(stroke
				(width 0.1)
				(type default)
			)
			(layer "B.Fab")
		)
		(fp_line
			(start -0.12065 -0.3048)
			(end -0.67945 -0.3048)
			(stroke
				(width 0.1)
				(type default)
			)
			(layer "B.Fab")
		)
		(fp_line
			(start 0.12065 -0.305054)
			(end 0.12065 -0.2794)
			(stroke
				(width 0.1)
				(type default)
			)
			(layer "B.Fab")
		)
		(fp_line
			(start 0.67945 -0.305054)
			(end 0.12065 -0.305054)
			(stroke
				(width 0.1)
				(type default)
			)
			(layer "B.Fab")
		)
		(pad "1" smd circle
			(at 0.40005 0 90)
			(size 0 0)
			(layers "B.Cu" "B.Mask" "B.Paste")
			(net "JTAG_CPU1_TRST_N")
		)
		(pad "2" smd circle
			(at -0.40005 0 90)
			(size 0 0)
			(layers "B.Cu" "B.Mask" "B.Paste")
			(net "GND")
		)
	)
)
